(kicad_pcb
	(version 20241229)
	(generator "pcbnew")
	(generator_version "9.0")
	(general
		(thickness 1.599998)
		(legacy_teardrops no)
	)
	(paper "A4")
	(title_block
		(title "Artix - Datacenter Secure Control Module (DC-SCM)")
		(date "2024-11-06")
		(rev "1.1.3")
		(comment 9 "footprints 425-429 of 544")
	)
	(layers
		(0 "F.Cu" signal)
		(4 "In1.Cu" signal)
		(6 "In2.Cu" signal)
		(8 "In3.Cu" signal)
		(10 "In4.Cu" signal)
		(12 "In5.Cu" signal)
		(14 "In6.Cu" signal)
		(2 "B.Cu" signal)
		(9 "F.Adhes" user "F.Adhesive")
		(11 "B.Adhes" user "B.Adhesive")
		(13 "F.Paste" user)
		(15 "B.Paste" user)
		(5 "F.SilkS" user "F.Silkscreen")
		(7 "B.SilkS" user "B.Silkscreen")
		(1 "F.Mask" user)
		(3 "B.Mask" user)
		(17 "Dwgs.User" user "User.Drawings")
		(19 "Cmts.User" user "User.Comments")
		(21 "Eco1.User" user "User.Eco1")
		(23 "Eco2.User" user "User.Eco2")
		(25 "Edge.Cuts" user)
		(27 "Margin" user)
		(31 "F.CrtYd" user "F.Courtyard")
		(29 "B.CrtYd" user "B.Courtyard")
		(35 "F.Fab" user)
		(33 "B.Fab" user)
	)
	(footprint "antmicro-footprints:R_0402_1005Metric"
		(layer "B.Cu")
		(at 68.967 91.556 -90)
		(descr "Resistor SMD 0402")
		(tags "resistor SMD 0402")
		(property "Reference" "R65"
			(at 1.884 -0.353 90)
			(layer "B.SilkS")
			(effects
				(font
					(size 0.7 0.7)
					(thickness 0.15)
				)
				(justify left bottom mirror)
			)
		)
		(property "Value" "R_100k_0402"
			(at 0 -1.4 90)
			(layer "B.Fab")
			(effects
				(font
					(size 0.7 0.7)
					(thickness 0.15)
				)
				(justify left bottom mirror)
			)
		)
		(property "Datasheet" "https://www.bourns.com/docs/product-datasheets/cr.pdf"
			(at 0 0 270)
			(layer "F.Fab")
			(hide yes)
			(effects
				(font
					(size 1.27 1.27)
					(thickness 0.15)
				)
			)
		)
		(property "Description" "SMD Chip Resistor, 100 kohm, ± 1%, 62.5 mW, 0402 [1005 Metric], Thick Film, General Purpose"
			(at 0 0 270)
			(layer "F.Fab")
			(hide yes)
			(effects
				(font
					(size 1.27 1.27)
					(thickness 0.15)
				)
			)
		)
		(property "Author" "Antmicro"
			(at -22.589 160.523 0)
			(layer "B.Fab")
			(hide yes)
			(effects
				(font
					(size 1 1)
					(thickness 0.15)
				)
				(justify mirror)
			)
		)
		(property "License" "Apache-2.0"
			(at -22.589 160.523 0)
			(layer "B.Fab")
			(hide yes)
			(effects
				(font
					(size 1 1)
					(thickness 0.15)
				)
				(justify mirror)
			)
		)
		(property "MPN" "CR0402-FX-1003GLF"
			(at -22.589 160.523 0)
			(layer "B.Fab")
			(hide yes)
			(effects
				(font
					(size 1 1)
					(thickness 0.15)
				)
				(justify mirror)
			)
		)
		(property "Manufacturer" "Bourns"
			(at -22.589 160.523 0)
			(layer "B.Fab")
			(hide yes)
			(effects
				(font
					(size 1 1)
					(thickness 0.15)
				)
				(justify mirror)
			)
		)
		(property "Tolerance" "1%"
			(at -22.589 160.523 0)
			(layer "B.Fab")
			(hide yes)
			(effects
				(font
					(size 1 1)
					(thickness 0.15)
				)
				(justify mirror)
			)
		)
		(property "Val" "100k"
			(at -22.589 160.523 0)
			(layer "B.Fab")
			(hide yes)
			(effects
				(font
					(size 1 1)
					(thickness 0.15)
				)
				(justify mirror)
			)
		)
		(sheetname "/Power supply/")
		(sheetfile "power-supply.kicad_sch")
		(attr smd)
		(fp_rect
			(start -0.925 0.47)
			(end 0.925 -0.47)
			(stroke
				(width 0.05)
				(type default)
			)
			(fill no)
			(layer "B.CrtYd")
		)
		(fp_rect
			(start -0.5 0.25)
			(end 0.5 -0.25)
			(stroke
				(width 0.15)
				(type solid)
			)
			(fill no)
			(layer "B.Fab")
		)
		(pad "1" smd roundrect
			(at -0.48 0 270)
			(size 0.59 0.64)
			(layers "B.Cu" "B.Mask" "B.Paste")
			(roundrect_rratio 0.25)
			(net 4 "VCC5V0")
			(pintype "passive")
		)
		(pad "2" smd roundrect
			(at 0.48 0 270)
			(size 0.59 0.64)
			(layers "B.Cu" "B.Mask" "B.Paste")
			(roundrect_rratio 0.25)
			(net 297 "/Power supply/VCCIO_EN")
			(pintype "passive")
		)
	)
	(footprint "antmicro-footprints:C_0402_1005Metric"
		(layer "B.Cu")
		(at 64.565 146.325 90)
		(descr "Capacitor SMD 0402")
		(tags "capacitor SMD 0402")
		(property "Reference" "C38"
			(at -1.095 -0.575 90)
			(layer "B.SilkS")
			(effects
				(font
					(size 0.7 0.7)
					(thickness 0.15)
				)
				(justify right bottom mirror)
			)
		)
		(property "Value" "C_470n_0402"
			(at 0 -1.4 90)
			(layer "B.Fab")
			(effects
				(font
					(size 0.7 0.7)
					(thickness 0.15)
				)
				(justify right bottom mirror)
			)
		)
		(property "Datasheet" "https://product.tdk.com/en/search/capacitor/ceramic/mlcc/info?part_no=C1005X5R1E474M050BB"
			(at 0 0 90)
			(layer "F.Fab")
			(hide yes)
			(effects
				(font
					(size 1.27 1.27)
					(thickness 0.15)
				)
			)
		)
		(property "Description" "SMD Multilayer Ceramic Capacitor, 0.47 µF, 25 V, 0402 [1005 Metric], ± 20%, X5R, C"
			(at 0 0 90)
			(layer "F.Fab")
			(hide yes)
			(effects
				(font
					(size 1.27 1.27)
					(thickness 0.15)
				)
			)
		)
		(property "Author" "Antmicro"
			(at 210.89 81.76 0)
			(layer "B.Fab")
			(hide yes)
			(effects
				(font
					(size 1 1)
					(thickness 0.15)
				)
				(justify mirror)
			)
		)
		(property "Dielectric" ""
			(at 210.89 81.76 0)
			(layer "B.Fab")
			(hide yes)
			(effects
				(font
					(size 1 1)
					(thickness 0.15)
				)
				(justify mirror)
			)
		)
		(property "License" "Apache-2.0"
			(at 210.89 81.76 0)
			(layer "B.Fab")
			(hide yes)
			(effects
				(font
					(size 1 1)
					(thickness 0.15)
				)
				(justify mirror)
			)
		)
		(property "MPN" "C1005X5R1E474M050BB"
			(at 210.89 81.76 0)
			(layer "B.Fab")
			(hide yes)
			(effects
				(font
					(size 1 1)
					(thickness 0.15)
				)
				(justify mirror)
			)
		)
		(property "Manufacturer" "TDK"
			(at 210.89 81.76 0)
			(layer "B.Fab")
			(hide yes)
			(effects
				(font
					(size 1 1)
					(thickness 0.15)
				)
				(justify mirror)
			)
		)
		(property "Val" "470n"
			(at 210.89 81.76 0)
			(layer "B.Fab")
			(hide yes)
			(effects
				(font
					(size 1 1)
					(thickness 0.15)
				)
				(justify mirror)
			)
		)
		(property "Voltage" ""
			(at 210.89 81.76 0)
			(layer "B.Fab")
			(hide yes)
			(effects
				(font
					(size 1 1)
					(thickness 0.15)
				)
				(justify mirror)
			)
		)
		(sheetname "/RoT/")
		(sheetfile "rot.kicad_sch")
		(attr smd)
		(fp_rect
			(start -0.925 0.47)
			(end 0.925 -0.47)
			(stroke
				(width 0.05)
				(type default)
			)
			(fill no)
			(layer "B.CrtYd")
		)
		(fp_line
			(start 0.504 -0.248)
			(end -0.494 -0.248)
			(stroke
				(width 0.15)
				(type solid)
			)
			(layer "B.Fab")
		)
		(fp_line
			(start -0.494 -0.248)
			(end -0.494 0.25)
			(stroke
				(width 0.15)
				(type solid)
			)
			(layer "B.Fab")
		)
		(fp_line
			(start 0.504 0.25)
			(end 0.504 -0.248)
			(stroke
				(width 0.15)
				(type solid)
			)
			(layer "B.Fab")
		)
		(fp_line
			(start -0.494 0.25)
			(end 0.504 0.25)
			(stroke
				(width 0.15)
				(type solid)
			)
			(layer "B.Fab")
		)
		(pad "1" smd roundrect
			(at -0.48 0 90)
			(size 0.59 0.64)
			(layers "B.Cu" "B.Mask" "B.Paste")
			(roundrect_rratio 0.25)
			(net 1 "GND")
			(pintype "passive")
		)
		(pad "2" smd roundrect
			(at 0.48 0 90)
			(size 0.59 0.64)
			(layers "B.Cu" "B.Mask" "B.Paste")
			(roundrect_rratio 0.25)
			(net 2 "VCC3V3")
			(pintype "passive")
		)
	)
	(footprint "antmicro-footprints:C_0402_1005Metric"
		(layer "B.Cu")
		(at 94.845 162.485 90)
		(descr "Capacitor SMD 0402")
		(tags "capacitor SMD 0402")
		(property "Reference" "C195"
			(at -3.715 0.375 90)
			(layer "B.SilkS")
			(effects
				(font
					(size 0.7 0.7)
					(thickness 0.15)
				)
				(justify right bottom mirror)
			)
		)
		(property "Value" "C_100n_6V3_0402"
			(at 0 -1.4 90)
			(layer "B.Fab")
			(effects
				(font
					(size 0.7 0.7)
					(thickness 0.15)
				)
				(justify right bottom mirror)
			)
		)
		(property "Datasheet" "https://www.passivecomponent.com/wp-content/uploads/datasheet/WTC_MLCC_General_Purpose.pdf"
			(at 0 0 90)
			(layer "F.Fab")
			(hide yes)
			(effects
				(font
					(size 1.27 1.27)
					(thickness 0.15)
				)
			)
		)
		(property "Description" "SMT Multilayer Ceramic Capacitor, 0.1 µF, 6.3 V, 0402 [1005 Metric], ± 10%, X5R, Walsin MLCC"
			(at 0 0 90)
			(layer "F.Fab")
			(hide yes)
			(effects
				(font
					(size 1.27 1.27)
					(thickness 0.15)
				)
			)
		)
		(property "Author" "Antmicro"
			(at 257.33 67.64 0)
			(layer "B.Fab")
			(hide yes)
			(effects
				(font
					(size 1 1)
					(thickness 0.15)
				)
				(justify mirror)
			)
		)
		(property "Dielectric" ""
			(at 257.33 67.64 0)
			(layer "B.Fab")
			(hide yes)
			(effects
				(font
					(size 1 1)
					(thickness 0.15)
				)
				(justify mirror)
			)
		)
		(property "License" "Apache-2.0"
			(at 257.33 67.64 0)
			(layer "B.Fab")
			(hide yes)
			(effects
				(font
					(size 1 1)
					(thickness 0.15)
				)
				(justify mirror)
			)
		)
		(property "MPN" "0402X104K6R3CT"
			(at 257.33 67.64 0)
			(layer "B.Fab")
			(hide yes)
			(effects
				(font
					(size 1 1)
					(thickness 0.15)
				)
				(justify mirror)
			)
		)
		(property "Manufacturer" "Walsin"
			(at 257.33 67.64 0)
			(layer "B.Fab")
			(hide yes)
			(effects
				(font
					(size 1 1)
					(thickness 0.15)
				)
				(justify mirror)
			)
		)
		(property "Public" "False"
			(at 257.33 67.64 0)
			(layer "B.Fab")
			(hide yes)
			(effects
				(font
					(size 1 1)
					(thickness 0.15)
				)
				(justify mirror)
			)
		)
		(property "Val" "100n"
			(at 257.33 67.64 0)
			(layer "B.Fab")
			(hide yes)
			(effects
				(font
					(size 1 1)
					(thickness 0.15)
				)
				(justify mirror)
			)
		)
		(property "Voltage" ""
			(at 257.33 67.64 0)
			(layer "B.Fab")
			(hide yes)
			(effects
				(font
					(size 1 1)
					(thickness 0.15)
				)
				(justify mirror)
			)
		)
		(sheetname "/Interfaces/")
		(sheetfile "interfaces.kicad_sch")
		(attr smd)
		(fp_rect
			(start -0.925 0.47)
			(end 0.925 -0.47)
			(stroke
				(width 0.05)
				(type default)
			)
			(fill no)
			(layer "B.CrtYd")
		)
		(fp_line
			(start 0.504 -0.248)
			(end -0.494 -0.248)
			(stroke
				(width 0.15)
				(type solid)
			)
			(layer "B.Fab")
		)
		(fp_line
			(start -0.494 -0.248)
			(end -0.494 0.25)
			(stroke
				(width 0.15)
				(type solid)
			)
			(layer "B.Fab")
		)
		(fp_line
			(start 0.504 0.25)
			(end 0.504 -0.248)
			(stroke
				(width 0.15)
				(type solid)
			)
			(layer "B.Fab")
		)
		(fp_line
			(start -0.494 0.25)
			(end 0.504 0.25)
			(stroke
				(width 0.15)
				(type solid)
			)
			(layer "B.Fab")
		)
		(pad "1" smd roundrect
			(at -0.48 0 90)
			(size 0.59 0.64)
			(layers "B.Cu" "B.Mask" "B.Paste")
			(roundrect_rratio 0.25)
			(net 378 "PCIE_BMC_TX_P")
			(pintype "passive")
		)
		(pad "2" smd roundrect
			(at 0.48 0 90)
			(size 0.59 0.64)
			(layers "B.Cu" "B.Mask" "B.Paste")
			(roundrect_rratio 0.25)
			(net 490 "/Interfaces/PCIE_BMC_TX_C_P")
			(pintype "passive")
		)
	)
	(footprint "antmicro-footprints:C_1210_3225Metric"
		(layer "B.Cu")
		(at 96.4 103.127 180)
		(descr "Capacitor SMD 1210")
		(tags "capacitor SMD 1210")
		(property "Reference" "C147"
			(at 1.9 -0.373 0)
			(layer "B.SilkS")
			(effects
				(font
					(size 0.7 0.7)
					(thickness 0.15)
				)
				(justify left bottom mirror)
			)
		)
		(property "Value" "C_47u_1210"
			(at 0 -2.749 0)
			(layer "B.Fab")
			(effects
				(font
					(size 0.7 0.7)
					(thickness 0.15)
				)
				(justify left bottom mirror)
			)
		)
		(property "Datasheet" "https://www.kemet.com/en/us/capacitors/product/C1210C476K8RACTU.html"
			(at 0 0 180)
			(layer "F.Fab")
			(hide yes)
			(effects
				(font
					(size 1.27 1.27)
					(thickness 0.15)
				)
			)
		)
		(property "Description" "SMD Multilayer Ceramic Capacitor, 47 µF, 10 V, 1210 [3225 Metric], ± 10%, X7R, C Series KEMET"
			(at 0 0 180)
			(layer "F.Fab")
			(hide yes)
			(effects
				(font
					(size 1.27 1.27)
					(thickness 0.15)
				)
			)
		)
		(property "Author" "Antmicro"
			(at 192.8 206.254 0)
			(layer "B.Fab")
			(hide yes)
			(effects
				(font
					(size 1 1)
					(thickness 0.15)
				)
				(justify mirror)
			)
		)
		(property "Dielectric" ""
			(at 192.8 206.254 0)
			(layer "B.Fab")
			(hide yes)
			(effects
				(font
					(size 1 1)
					(thickness 0.15)
				)
				(justify mirror)
			)
		)
		(property "License" "Apache-2.0"
			(at 192.8 206.254 0)
			(layer "B.Fab")
			(hide yes)
			(effects
				(font
					(size 1 1)
					(thickness 0.15)
				)
				(justify mirror)
			)
		)
		(property "MPN" "C1210C476K8RACTU"
			(at 192.8 206.254 0)
			(layer "B.Fab")
			(hide yes)
			(effects
				(font
					(size 1 1)
					(thickness 0.15)
				)
				(justify mirror)
			)
		)
		(property "Manufacturer" "KEMET"
			(at 192.8 206.254 0)
			(layer "B.Fab")
			(hide yes)
			(effects
				(font
					(size 1 1)
					(thickness 0.15)
				)
				(justify mirror)
			)
		)
		(property "Public" "False"
			(at 192.8 206.254 0)
			(layer "B.Fab")
			(hide yes)
			(effects
				(font
					(size 1 1)
					(thickness 0.15)
				)
				(justify mirror)
			)
		)
		(property "Val" "47u"
			(at 192.8 206.254 0)
			(layer "B.Fab")
			(hide yes)
			(effects
				(font
					(size 1 1)
					(thickness 0.15)
				)
				(justify mirror)
			)
		)
		(property "Voltage" ""
			(at 192.8 206.254 0)
			(layer "B.Fab")
			(hide yes)
			(effects
				(font
					(size 1 1)
					(thickness 0.15)
				)
				(justify mirror)
			)
		)
		(property "DNP" ""
			(at 0 0 180)
			(unlocked yes)
			(layer "B.Fab")
			(hide yes)
			(effects
				(font
					(size 1 1)
					(thickness 0.15)
				)
				(justify mirror)
			)
		)
		(sheetname "/FPGA power supply/")
		(sheetfile "fpga-power-supply.kicad_sch")
		(attr smd)
		(fp_line
			(start -0.3 1.39)
			(end 0.3 1.39)
			(stroke
				(width 0.15)
				(type solid)
			)
			(layer "B.SilkS")
		)
		(fp_line
			(start -0.3 -1.39)
			(end 0.3 -1.39)
			(stroke
				(width 0.15)
				(type solid)
			)
			(layer "B.SilkS")
		)
		(fp_rect
			(start -2.1 1.75)
			(end 2.1 -1.75)
			(stroke
				(width 0.05)
				(type solid)
			)
			(fill no)
			(layer "B.CrtYd")
		)
		(fp_rect
			(start -1.6 1.25)
			(end 1.6 -1.25)
			(stroke
				(width 0.15)
				(type solid)
			)
			(fill no)
			(layer "B.Fab")
		)
		(pad "1" smd rect
			(at -1.145 0 180)
			(size 1.52 3.05)
			(layers "B.Cu" "B.Mask" "B.Paste")
			(net 1 "GND")
			(pintype "passive")
		)
		(pad "2" smd rect
			(at 1.145 0 180)
			(size 1.52 3.05)
			(layers "B.Cu" "B.Mask" "B.Paste")
			(net 6 "VCC1V0")
			(pintype "passive")
		)
	)
	(footprint "antmicro-footprints:C_0402_1005Metric"
		(layer "B.Cu")
		(at 64.575 136.705 90)
		(descr "Capacitor SMD 0402")
		(tags "capacitor SMD 0402")
		(property "Reference" "C37"
			(at -1.095 -0.575 90)
			(layer "B.SilkS")
			(effects
				(font
					(size 0.7 0.7)
					(thickness 0.15)
				)
				(justify right bottom mirror)
			)
		)
		(property "Value" "C_470n_0402"
			(at 0 -1.4 90)
			(layer "B.Fab")
			(effects
				(font
					(size 0.7 0.7)
					(thickness 0.15)
				)
				(justify right bottom mirror)
			)
		)
		(property "Datasheet" "https://product.tdk.com/en/search/capacitor/ceramic/mlcc/info?part_no=C1005X5R1E474M050BB"
			(at 0 0 90)
			(layer "F.Fab")
			(hide yes)
			(effects
				(font
					(size 1.27 1.27)
					(thickness 0.15)
				)
			)
		)
		(property "Description" "SMD Multilayer Ceramic Capacitor, 0.47 µF, 25 V, 0402 [1005 Metric], ± 20%, X5R, C"
			(at 0 0 90)
			(layer "F.Fab")
			(hide yes)
			(effects
				(font
					(size 1.27 1.27)
					(thickness 0.15)
				)
			)
		)
		(property "Author" "Antmicro"
			(at 201.28 72.13 0)
			(layer "B.Fab")
			(hide yes)
			(effects
				(font
					(size 1 1)
					(thickness 0.15)
				)
				(justify mirror)
			)
		)
		(property "Dielectric" ""
			(at 201.28 72.13 0)
			(layer "B.Fab")
			(hide yes)
			(effects
				(font
					(size 1 1)
					(thickness 0.15)
				)
				(justify mirror)
			)
		)
		(property "License" "Apache-2.0"
			(at 201.28 72.13 0)
			(layer "B.Fab")
			(hide yes)
			(effects
				(font
					(size 1 1)
					(thickness 0.15)
				)
				(justify mirror)
			)
		)
		(property "MPN" "C1005X5R1E474M050BB"
			(at 201.28 72.13 0)
			(layer "B.Fab")
			(hide yes)
			(effects
				(font
					(size 1 1)
					(thickness 0.15)
				)
				(justify mirror)
			)
		)
		(property "Manufacturer" "TDK"
			(at 201.28 72.13 0)
			(layer "B.Fab")
			(hide yes)
			(effects
				(font
					(size 1 1)
					(thickness 0.15)
				)
				(justify mirror)
			)
		)
		(property "Val" "470n"
			(at 201.28 72.13 0)
			(layer "B.Fab")
			(hide yes)
			(effects
				(font
					(size 1 1)
					(thickness 0.15)
				)
				(justify mirror)
			)
		)
		(property "Voltage" ""
			(at 201.28 72.13 0)
			(layer "B.Fab")
			(hide yes)
			(effects
				(font
					(size 1 1)
					(thickness 0.15)
				)
				(justify mirror)
			)
		)
		(sheetname "/RoT/")
		(sheetfile "rot.kicad_sch")
		(attr smd)
		(fp_rect
			(start -0.925 0.47)
			(end 0.925 -0.47)
			(stroke
				(width 0.05)
				(type default)
			)
			(fill no)
			(layer "B.CrtYd")
		)
		(fp_line
			(start 0.504 -0.248)
			(end -0.494 -0.248)
			(stroke
				(width 0.15)
				(type solid)
			)
			(layer "B.Fab")
		)
		(fp_line
			(start -0.494 -0.248)
			(end -0.494 0.25)
			(stroke
				(width 0.15)
				(type solid)
			)
			(layer "B.Fab")
		)
		(fp_line
			(start 0.504 0.25)
			(end 0.504 -0.248)
			(stroke
				(width 0.15)
				(type solid)
			)
			(layer "B.Fab")
		)
		(fp_line
			(start -0.494 0.25)
			(end 0.504 0.25)
			(stroke
				(width 0.15)
				(type solid)
			)
			(layer "B.Fab")
		)
		(pad "1" smd roundrect
			(at -0.48 0 90)
			(size 0.59 0.64)
			(layers "B.Cu" "B.Mask" "B.Paste")
			(roundrect_rratio 0.25)
			(net 1 "GND")
			(pintype "passive")
		)
		(pad "2" smd roundrect
			(at 0.48 0 90)
			(size 0.59 0.64)
			(layers "B.Cu" "B.Mask" "B.Paste")
			(roundrect_rratio 0.25)
			(net 2 "VCC3V3")
			(pintype "passive")
		)
	)
)
